(kicad_pcb
	(version 20241229)
	(generator "pcbnew")
	(generator_version "9.0")
	(general
		(thickness 1.63)
		(legacy_teardrops no)
	)
	(paper "A4")
	(title_block
		(title "CM4 Baseboard")
		(date "2026-01-05")
		(rev "1.1.1")
		(company "Antmicro Ltd")
		(comment 1 "www.antmicro.com")
		(comment 9 "footprints 374-375 of 506")
	)
	(layers
		(0 "F.Cu" signal)
		(4 "In1.Cu" power)
		(6 "In2.Cu" power)
		(8 "In3.Cu" signal)
		(10 "In4.Cu" signal)
		(2 "B.Cu" signal)
		(9 "F.Adhes" user "F.Adhesive")
		(11 "B.Adhes" user "B.Adhesive")
		(13 "F.Paste" user)
		(15 "B.Paste" user)
		(5 "F.SilkS" user "F.Silkscreen")
		(7 "B.SilkS" user "B.Silkscreen")
		(1 "F.Mask" user)
		(3 "B.Mask" user)
		(17 "Dwgs.User" user "User.Drawings")
		(19 "Cmts.User" user "User.Comments")
		(21 "Eco1.User" user "User.Eco1")
		(23 "Eco2.User" user "User.Eco2")
		(25 "Edge.Cuts" user)
		(27 "Margin" user)
		(31 "F.CrtYd" user "F.Courtyard")
		(29 "B.CrtYd" user "B.Courtyard")
		(35 "F.Fab" user)
		(33 "B.Fab" user)
	)
	(footprint "antmicro-footprints:Nexperia_DFN-10_2.5x1mm_P0.5mm"
		(layer "B.Cu")
		(at 110.092962 116.7165 180)
		(property "Reference" "D708"
			(at 1.385 -0.43 0)
			(layer "B.SilkS")
			(effects
				(font
					(size 0.7 0.7)
					(thickness 0.15)
				)
				(justify left bottom mirror)
			)
		)
		(property "Value" "PUSB3F96X_PASS"
			(at -0.016 -1.705 0)
			(layer "B.Fab")
			(effects
				(font
					(size 0.7 0.7)
					(thickness 0.15)
				)
				(justify left bottom mirror)
			)
		)
		(property "Datasheet" "https://mouser.com/datasheet/2/916/PUSB3F96-1600324.pdf"
			(at 0 0 180)
			(layer "B.Fab")
			(hide yes)
			(effects
				(font
					(size 1.27 1.27)
					(thickness 0.15)
				)
			)
		)
		(property "Manufacturer" "Nexperia"
			(at 0 0 180)
			(unlocked yes)
			(layer "B.Fab")
			(hide yes)
			(effects
				(font
					(size 1 1)
					(thickness 0.15)
				)
				(justify mirror)
			)
		)
		(property "MPN" "PUSB3F96X"
			(at 0 0 180)
			(unlocked yes)
			(layer "B.Fab")
			(hide yes)
			(effects
				(font
					(size 1 1)
					(thickness 0.15)
				)
				(justify mirror)
			)
		)
		(property "Author" "Antmicro"
			(at 0 0 180)
			(unlocked yes)
			(layer "B.Fab")
			(hide yes)
			(effects
				(font
					(size 1 1)
					(thickness 0.15)
				)
				(justify mirror)
			)
		)
		(property "License" "Apache-2.0"
			(at 0 0 180)
			(unlocked yes)
			(layer "B.Fab")
			(hide yes)
			(effects
				(font
					(size 1 1)
					(thickness 0.15)
				)
				(justify mirror)
			)
		)
		(sheetname "/Display/")
		(sheetfile "display.kicad_sch")
		(attr smd)
		(fp_line
			(start 1.375 -0.4)
			(end 1.375 0.4)
			(stroke
				(width 0.15)
				(type solid)
			)
			(layer "B.SilkS")
		)
		(fp_line
			(start -1.375 0.4)
			(end -1.375 -0.4)
			(stroke
				(width 0.15)
				(type solid)
			)
			(layer "B.SilkS")
		)
		(fp_circle
			(center -1.4 -0.7)
			(end -1.349 -0.7)
			(stroke
				(width 0.15)
				(type solid)
			)
			(fill yes)
			(layer "B.SilkS")
		)
		(fp_rect
			(start -1.4 0.725)
			(end 1.4 -0.725)
			(stroke
				(width 0.05)
				(type solid)
			)
			(fill no)
			(layer "B.CrtYd")
		)
		(fp_line
			(start 1.25 0.5)
			(end -1.25 0.5)
			(stroke
				(width 0.15)
				(type solid)
			)
			(layer "B.Fab")
		)
		(fp_line
			(start 1.25 -0.5)
			(end 1.25 0.5)
			(stroke
				(width 0.15)
				(type solid)
			)
			(layer "B.Fab")
		)
		(fp_line
			(start -0.9 -0.5)
			(end 1.25 -0.5)
			(stroke
				(width 0.15)
				(type solid)
			)
			(layer "B.Fab")
		)
		(fp_line
			(start -1.25 0.5)
			(end -1.25 -0.15)
			(stroke
				(width 0.15)
				(type solid)
			)
			(layer "B.Fab")
		)
		(fp_line
			(start -1.25 -0.15)
			(end -0.9 -0.5)
			(stroke
				(width 0.15)
				(type solid)
			)
			(layer "B.Fab")
		)
		(fp_text user "License: Apache-2.0"
			(at -1.367 -6.105 0)
			(layer "B.Fab")
			(effects
				(font
					(size 0.7 0.7)
					(thickness 0.15)
				)
				(justify left bottom mirror)
			)
		)
		(fp_text user "Author: Antmicro"
			(at -1.367 -4.905 0)
			(layer "B.Fab")
			(effects
				(font
					(size 0.7 0.7)
					(thickness 0.15)
				)
				(justify left bottom mirror)
			)
		)
		(fp_text user "${REFERENCE}"
			(at -1.367 -3.704 0)
			(layer "B.Fab")
			(effects
				(font
					(size 0.7 0.7)
					(thickness 0.15)
				)
				(justify left bottom mirror)
			)
		)
		(pad "1" smd rect
			(at -1 -0.3875 180)
			(size 0.2 0.475)
			(layers "B.Cu" "B.Mask" "B.Paste")
			(net 262 "/Compute module/HDMI.HPD")
			(pinfunction "CH1")
			(pintype "passive")
			(solder_mask_margin 0.05)
		)
		(pad "2" smd rect
			(at -0.5 -0.3875 180)
			(size 0.2 0.475)
			(layers "B.Cu" "B.Mask" "B.Paste")
			(net 261 "/Compute module/HDMI.CEC")
			(pinfunction "CH2")
			(pintype "passive")
			(solder_mask_margin 0.05)
		)
		(pad "3" smd rect
			(at 0 -0.3875 180)
			(size 0.2 0.475)
			(layers "B.Cu" "B.Mask" "B.Paste")
			(net 3 "GND")
			(pinfunction "GND")
			(pintype "passive")
			(solder_mask_margin 0.05)
		)
		(pad "4" smd rect
			(at 0.5 -0.3875 180)
			(size 0.2 0.475)
			(layers "B.Cu" "B.Mask" "B.Paste")
			(net 267 "/Compute module/HDMI.SCL")
			(pinfunction "CH3")
			(pintype "passive")
			(solder_mask_margin 0.05)
		)
		(pad "5" smd rect
			(at 1 -0.3875 180)
			(size 0.2 0.475)
			(layers "B.Cu" "B.Mask" "B.Paste")
			(net 266 "/Compute module/HDMI.SDA")
			(pinfunction "CH4")
			(pintype "passive")
			(solder_mask_margin 0.05)
		)
		(pad "6" smd rect
			(at 1 0.3875 180)
			(size 0.2 0.475)
			(layers "B.Cu" "B.Mask" "B.Paste")
			(net 266 "/Compute module/HDMI.SDA")
			(pinfunction "CH4")
			(pintype "passive")
			(solder_mask_margin 0.05)
		)
		(pad "7" smd rect
			(at 0.5 0.3875 180)
			(size 0.2 0.475)
			(layers "B.Cu" "B.Mask" "B.Paste")
			(net 267 "/Compute module/HDMI.SCL")
			(pinfunction "CH3")
			(pintype "passive")
			(solder_mask_margin 0.05)
		)
		(pad "8" smd rect
			(at 0 0.3875 180)
			(size 0.2 0.475)
			(layers "B.Cu" "B.Mask" "B.Paste")
			(net 3 "GND")
			(pinfunction "GND")
			(pintype "passive")
			(solder_mask_margin 0.05)
		)
		(pad "9" smd rect
			(at -0.501 0.3875 180)
			(size 0.2 0.475)
			(layers "B.Cu" "B.Mask" "B.Paste")
			(net 261 "/Compute module/HDMI.CEC")
			(pinfunction "CH2")
			(pintype "passive")
			(solder_mask_margin 0.05)
		)
		(pad "10" smd rect
			(at -1 0.3875 180)
			(size 0.2 0.475)
			(layers "B.Cu" "B.Mask" "B.Paste")
			(net 262 "/Compute module/HDMI.HPD")
			(pinfunction "CH1")
			(pintype "passive")
			(solder_mask_margin 0.05)
		)
	)
	(footprint "antmicro-footprints:FB_0603_1608Metric"
		(layer "B.Cu")
		(at 113.627962 115.9865 180)
		(property "Reference" "FB701"
			(at -2.04 -6.055 0)
			(layer "B.SilkS")
			(effects
				(font
					(size 0.7 0.7)
					(thickness 0.15)
				)
				(justify left bottom mirror)
			)
		)
		(property "Value" "FB_220Z_2.2A_TDK-MPZ_0603"
			(at 0 -1.5 0)
			(layer "B.Fab")
			(effects
				(font
					(size 0.7 0.7)
					(thickness 0.15)
				)
				(justify left bottom mirror)
			)
		)
		(property "Datasheet" "https://product.tdk.com/info/en/catalog/datasheets/beads_commercial_power_mpz1608_en.pdf"
			(at 0 0 180)
			(layer "B.Fab")
			(hide yes)
			(effects
				(font
					(size 1.27 1.27)
					(thickness 0.15)
				)
			)
		)
		(property "MPN" "MPZ1608S221ATA00"
			(at 0 0 180)
			(unlocked yes)
			(layer "B.Fab")
			(hide yes)
			(effects
				(font
					(size 1 1)
					(thickness 0.15)
				)
				(justify mirror)
			)
		)
		(property "Manufacturer" "TDK"
			(at 0 0 180)
			(unlocked yes)
			(layer "B.Fab")
			(hide yes)
			(effects
				(font
					(size 1 1)
					(thickness 0.15)
				)
				(justify mirror)
			)
		)
		(property "Author" "Antmicro"
			(at 0 0 180)
			(unlocked yes)
			(layer "B.Fab")
			(hide yes)
			(effects
				(font
					(size 1 1)
					(thickness 0.15)
				)
				(justify mirror)
			)
		)
		(property "License" "Apache-2.0"
			(at 0 0 180)
			(unlocked yes)
			(layer "B.Fab")
			(hide yes)
			(effects
				(font
					(size 1 1)
					(thickness 0.15)
				)
				(justify mirror)
			)
		)
		(property "Val" "220Z/2.2A"
			(at 0 0 180)
			(unlocked yes)
			(layer "B.Fab")
			(hide yes)
			(effects
				(font
					(size 1 1)
					(thickness 0.15)
				)
				(justify mirror)
			)
		)
		(property "Current" ""
			(at 0 0 180)
			(unlocked yes)
			(layer "B.Fab")
			(hide yes)
			(effects
				(font
					(size 1 1)
					(thickness 0.15)
				)
				(justify mirror)
			)
		)
		(sheetname "/Display/")
		(sheetfile "display.kicad_sch")
		(attr smd)
		(fp_line
			(start -0.15 0.4)
			(end 0.15 0.4)
			(stroke
				(width 0.15)
				(type solid)
			)
			(layer "B.SilkS")
		)
		(fp_line
			(start -0.15 -0.4)
			(end 0.15 -0.4)
			(stroke
				(width 0.15)
				(type solid)
			)
			(layer "B.SilkS")
		)
		(fp_rect
			(start -1.25 0.65)
			(end 1.25 -0.65)
			(stroke
				(width 0.05)
				(type solid)
			)
			(fill no)
			(layer "B.CrtYd")
		)
		(fp_line
			(start 0.8 0.408)
			(end 0.8 -0.406)
			(stroke
				(width 0.15)
				(type solid)
			)
			(layer "B.Fab")
		)
		(fp_line
			(start 0.8 0.408)
			(end -0.803 0.408)
			(stroke
				(width 0.15)
				(type solid)
			)
			(layer "B.Fab")
		)
		(fp_line
			(start 0.8 -0.406)
			(end -0.803 -0.406)
			(stroke
				(width 0.15)
				(type solid)
			)
			(layer "B.Fab")
		)
		(fp_line
			(start -0.803 -0.406)
			(end -0.803 0.408)
			(stroke
				(width 0.15)
				(type solid)
			)
			(layer "B.Fab")
		)
		(fp_text user "Author: Antmicro"
			(at -1.653 -3.162 0)
			(layer "B.Fab")
			(effects
				(font
					(size 0.7 0.7)
					(thickness 0.15)
				)
				(justify left bottom mirror)
			)
		)
		(fp_text user "License: Apache-2.0"
			(at -1.653 -5.9 0)
			(layer "B.Fab")
			(effects
				(font
					(size 0.7 0.7)
					(thickness 0.15)
				)
				(justify left bottom mirror)
			)
		)
		(fp_text user "${REFERENCE}"
			(at -1.653 -4.6 0)
			(layer "B.Fab")
			(effects
				(font
					(size 0.7 0.7)
					(thickness 0.15)
				)
				(justify left bottom mirror)
			)
		)
		(pad "1" smd roundrect
			(at -0.7 0 180)
			(size 0.8 1)
			(layers "B.Cu" "B.Mask" "B.Paste")
			(roundrect_rratio 0.2)
			(net 10 "+5V")
			(pintype "passive")
		)
		(pad "2" smd roundrect
			(at 0.7 0 180)
			(size 0.8 1)
			(layers "B.Cu" "B.Mask" "B.Paste")
			(roundrect_rratio 0.2)
			(net 481 "Net-(D710-A)")
			(pintype "passive")
		)
	)
)
